# BASEBOARD_FAB2 (Tioga Pass) — schematic netlist excerpt (pin names and nets, part order shuffled) for the footprints in the layout excerpt that follows; sources: Cadence DE-HDL packaged netlist, KiCad conversion of Wiwynn_Tioga_Pass_MB.brd

C8D2  CAP_A  0.1UF 16V 10% X7R  pkg 0402V  page 170 : A = P3V3_STBY ; B = GND
C1C26  CAP  1.0UF 16V 10% X6S  pkg 0402  page 209 : A = VR_FET_SW_P12V_STBY_PVCCIN_CPU1 ; B = GND
R4G5  RES  10.0K 1% CHIP  pkg 0402  page 233 : A = FM_PVPP_CPU1_EN ; B = GND

(kicad_pcb
	(version 20260206)
	(generator "pcbnew")
	(generator_version "10.0")
	(general
		(thickness 1.6)
		(legacy_teardrops no)
	)
	(paper "A4")
	(title_block
		(title "Wiwynn_Tioga_Pass_MB.brd")
		(comment 1 "Tioga Pass / footprints 1115-1117 of 4770")
	)
	(layers
		(0 "F.Cu" signal "TOP")
		(4 "In1.Cu" signal "L2GND")
		(6 "In2.Cu" signal "L3")
		(8 "In3.Cu" signal "L4GND")
		(10 "In4.Cu" signal "L5")
		(12 "In5.Cu" signal "L6GND")
		(14 "In6.Cu" signal "L7VCC")
		(16 "In7.Cu" signal "L8VCC")
		(18 "In8.Cu" signal "L9GND")
		(20 "In9.Cu" signal "L10")
		(22 "In10.Cu" signal "L11GND")
		(24 "In11.Cu" signal "L12")
		(26 "In12.Cu" signal "L13GND")
		(2 "B.Cu" signal "BOTTOM")
		(9 "F.Adhes" user "F.Adhesive")
		(11 "B.Adhes" user "B.Adhesive")
		(13 "F.Paste" user "Package Geometry/Pastemask Top")
		(15 "B.Paste" user "Package Geometry/Pastemask Bottom")
		(5 "F.SilkS" user "Ref Des/Silkscreen Top")
		(7 "B.SilkS" user "Ref Des/Silkscreen Bottom")
		(1 "F.Mask" user "Board Geometry/Soldermask Top")
		(3 "B.Mask" user "Board Geometry/Soldermask Bottom")
		(17 "Dwgs.User" user "User.Drawings")
		(19 "Cmts.User" user "User.Comments")
		(21 "Eco1.User" user "User.Eco1")
		(23 "Eco2.User" user "User.Eco2")
		(25 "Edge.Cuts" user "Board Geometry/Outline")
		(27 "Margin" user)
		(31 "F.CrtYd" user "Package Geometry/Place Bound Top")
		(29 "B.CrtYd" user "Package Geometry/Place Bound Bottom")
		(35 "F.Fab" user "Ref Des/Assembly Top")
		(33 "B.Fab" user "Ref Des/Assembly Bottom")
	)
	(footprint ""
		(layer "F.Cu")
		(at 420.7256 -86.4235)
		(property "Reference" "C8D2"
			(at 0 0 0)
			(layer "F.SilkS")
			(hide yes)
			(effects
				(font
					(size 1.27 1.27)
				)
			)
		)
		(property "Value" ""
			(at 0 0 0)
			(layer "F.Fab")
			(effects
				(font
					(size 1.27 1.27)
				)
			)
		)
		(duplicate_pad_numbers_are_jumpers no)
		(fp_poly
			(pts
				(xy 0.3048 -0.1016) (xy 0.3048 0.9906) (xy -0.3048 0.9906) (xy -0.3048 -0.1016)
			)
			(stroke
				(width 0)
				(type default)
			)
			(fill no)
			(layer "F.CrtYd")
		)
		(fp_line
			(start -0.3048 -0.1016)
			(end -0.3048 0.9906)
			(stroke
				(width 0.1)
				(type default)
			)
			(layer "F.Fab")
		)
		(fp_line
			(start -0.3048 0.9906)
			(end 0.3048 0.9906)
			(stroke
				(width 0.1)
				(type default)
			)
			(layer "F.Fab")
		)
		(fp_line
			(start 0.3048 -0.1016)
			(end -0.3048 -0.1016)
			(stroke
				(width 0.1)
				(type default)
			)
			(layer "F.Fab")
		)
		(fp_line
			(start 0.3048 0.9906)
			(end 0.3048 -0.1016)
			(stroke
				(width 0.1)
				(type default)
			)
			(layer "F.Fab")
		)
		(pad "1" smd rect
			(at 0 0)
			(size 0.508 0.508)
			(layers "F.Cu" "F.Mask" "F.Paste")
			(net "P3V3_STBY")
		)
		(pad "2" smd rect
			(at 0 0.889)
			(size 0.508 0.508)
			(layers "F.Cu" "F.Mask" "F.Paste")
			(net "GND")
		)
		(zone
			(layer "F.Cu")
			(hatch none 0.5)
			(connect_pads
				(clearance 0)
			)
			(min_thickness 0.25)
			(keepout
				(tracks allowed)
				(vias not_allowed)
				(pads allowed)
				(copperpour not_allowed)
				(footprints allowed)
			)
			(placement
				(enabled no)
				(sheetname "")
			)
			(fill
				(thermal_gap 0.5)
				(thermal_bridge_width 0.5)
				(island_removal_mode 0)
			)
			(polygon
				(pts
					(xy 420.4716 -86.1695) (xy 420.9796 -86.1695) (xy 420.9796 -85.7885) (xy 420.4716 -85.7885)
				)
			)
		)
		(zone
			(layer "F.Cu")
			(hatch none 0.5)
			(connect_pads
				(clearance 0)
			)
			(min_thickness 0.25)
			(keepout
				(tracks not_allowed)
				(vias allowed)
				(pads allowed)
				(copperpour not_allowed)
				(footprints allowed)
			)
			(placement
				(enabled no)
				(sheetname "")
			)
			(fill
				(thermal_gap 0.5)
				(thermal_bridge_width 0.5)
				(island_removal_mode 0)
			)
			(polygon
				(pts
					(xy 420.4716 -85.7885) (xy 420.9796 -85.7885) (xy 420.9796 -86.1695) (xy 420.4716 -86.1695)
				)
			)
		)
	)
	(footprint ""
		(layer "F.Cu")
		(at 170.9166 -8.6614)
		(property "Reference" "R4G5"
			(at 0 0 0)
			(layer "F.SilkS")
			(hide yes)
			(effects
				(font
					(size 1.27 1.27)
				)
			)
		)
		(property "Value" ""
			(at 0 0 0)
			(layer "F.Fab")
			(effects
				(font
					(size 1.27 1.27)
				)
			)
		)
		(duplicate_pad_numbers_are_jumpers no)
		(fp_rect
			(start -0.2794 0.9906)
			(end 0.2794 -0.1016)
			(stroke
				(width 0)
				(type default)
			)
			(fill no)
			(layer "F.CrtYd")
		)
		(fp_line
			(start -0.2794 -0.1016)
			(end -0.2794 0.9906)
			(stroke
				(width 0.1)
				(type default)
			)
			(layer "F.Fab")
		)
		(fp_line
			(start -0.2794 0.9906)
			(end 0.2794 0.9906)
			(stroke
				(width 0.1)
				(type default)
			)
			(layer "F.Fab")
		)
		(fp_line
			(start 0.2794 -0.1016)
			(end -0.2794 -0.1016)
			(stroke
				(width 0.1)
				(type default)
			)
			(layer "F.Fab")
		)
		(fp_line
			(start 0.2794 0.9906)
			(end 0.2794 -0.1016)
			(stroke
				(width 0.1)
				(type default)
			)
			(layer "F.Fab")
		)
		(pad "1" smd rect
			(at 0 0)
			(size 0.508 0.508)
			(layers "F.Cu" "F.Mask" "F.Paste")
			(net "FM_PVPP_CPU1_EN")
		)
		(pad "2" smd rect
			(at 0 0.889)
			(size 0.508 0.508)
			(layers "F.Cu" "F.Mask" "F.Paste")
			(net "GND")
		)
		(zone
			(layer "F.Cu")
			(hatch none 0.5)
			(connect_pads
				(clearance 0)
			)
			(min_thickness 0.25)
			(keepout
				(tracks not_allowed)
				(vias allowed)
				(pads allowed)
				(copperpour not_allowed)
				(footprints allowed)
			)
			(placement
				(enabled no)
				(sheetname "")
			)
			(fill
				(thermal_gap 0.5)
				(thermal_bridge_width 0.5)
				(island_removal_mode 0)
			)
			(polygon
				(pts
					(xy 170.6626 -8.0264) (xy 171.1706 -8.0264) (xy 171.1706 -8.4074) (xy 170.6626 -8.4074)
				)
			)
		)
		(zone
			(layer "F.Cu")
			(hatch none 0.5)
			(connect_pads
				(clearance 0)
			)
			(min_thickness 0.25)
			(keepout
				(tracks allowed)
				(vias not_allowed)
				(pads allowed)
				(copperpour not_allowed)
				(footprints allowed)
			)
			(placement
				(enabled no)
				(sheetname "")
			)
			(fill
				(thermal_gap 0.5)
				(thermal_bridge_width 0.5)
				(island_removal_mode 0)
			)
			(polygon
				(pts
					(xy 170.6626 -8.0264) (xy 171.1706 -8.0264) (xy 171.1706 -8.4074) (xy 170.6626 -8.4074)
				)
			)
		)
	)
	(footprint ""
		(layer "F.Cu")
		(at 29.083 -92.3798 -90)
		(property "Reference" "C1C26"
			(at 0 0 270)
			(layer "F.SilkS")
			(hide yes)
			(effects
				(font
					(size 1.27 1.27)
				)
			)
		)
		(property "Value" ""
			(at 0 0 270)
			(layer "F.Fab")
			(effects
				(font
					(size 1.27 1.27)
				)
			)
		)
		(duplicate_pad_numbers_are_jumpers no)
		(fp_rect
			(start 0.3048 -0.1016)
			(end -0.3048 0.9906)
			(stroke
				(width 0)
				(type default)
			)
			(fill no)
			(layer "F.CrtYd")
		)
		(fp_line
			(start -0.3048 0.9906)
			(end 0.3048 0.9906)
			(stroke
				(width 0.1)
				(type default)
			)
			(layer "F.Fab")
		)
		(fp_line
			(start 0.3048 0.9906)
			(end 0.3048 -0.1016)
			(stroke
				(width 0.1)
				(type default)
			)
			(layer "F.Fab")
		)
		(fp_line
			(start -0.3048 -0.1016)
			(end -0.3048 0.9906)
			(stroke
				(width 0.1)
				(type default)
			)
			(layer "F.Fab")
		)
		(fp_line
			(start 0.3048 -0.1016)
			(end -0.3048 -0.1016)
			(stroke
				(width 0.1)
				(type default)
			)
			(layer "F.Fab")
		)
		(pad "1" smd rect
			(at 0 0 270)
			(size 0.508 0.508)
			(layers "F.Cu" "F.Mask" "F.Paste")
			(net "VR_FET_SW_P12V_STBY_PVCCIN_CPU1")
		)
		(pad "2" smd rect
			(at 0 0.889 270)
			(size 0.508 0.508)
			(layers "F.Cu" "F.Mask" "F.Paste")
			(net "GND")
		)
		(zone
			(layer "F.Cu")
			(hatch none 0.5)
			(connect_pads
				(clearance 0)
			)
			(min_thickness 0.25)
			(keepout
				(tracks allowed)
				(vias not_allowed)
				(pads allowed)
				(copperpour not_allowed)
				(footprints allowed)
			)
			(placement
				(enabled no)
				(sheetname "")
			)
			(fill
				(thermal_gap 0.5)
				(thermal_bridge_width 0.5)
				(island_removal_mode 0)
			)
			(polygon
				(pts
					(xy 28.829 -92.1258) (xy 28.829 -92.6338) (xy 28.448 -92.6338) (xy 28.448 -92.1258)
				)
			)
		)
		(zone
			(layer "F.Cu")
			(hatch none 0.5)
			(connect_pads
				(clearance 0)
			)
			(min_thickness 0.25)
			(keepout
				(tracks not_allowed)
				(vias allowed)
				(pads allowed)
				(copperpour not_allowed)
				(footprints allowed)
			)
			(placement
				(enabled no)
				(sheetname "")
			)
			(fill
				(thermal_gap 0.5)
				(thermal_bridge_width 0.5)
				(island_removal_mode 0)
			)
			(polygon
				(pts
					(xy 28.829 -92.1258) (xy 28.829 -92.6338) (xy 28.448 -92.6338) (xy 28.448 -92.1258)
				)
			)
		)
	)
)
